(kicad_pcb
	(version 20260206)
	(generator "pcbnew")
	(generator_version "10.0")
	(general
		(thickness 1.21888)
		(legacy_teardrops no)
	)
	(paper "A4")
	(title_block
		(title "timecard-v8 — TimeCard-DC-V8_EXP.PcbDoc")
		(comment 1 "Time Appliance Project (Time Card) / footprints 264-271 of 288")
	)
	(layers
		(0 "F.Cu" signal "TOP")
		(4 "In1.Cu" signal "SGND")
		(6 "In2.Cu" signal "IN1")
		(8 "In3.Cu" signal "IN2")
		(10 "In4.Cu" signal "SGND1")
		(2 "B.Cu" signal "BOTTOM")
		(9 "F.Adhes" user "F.Adhesive")
		(11 "B.Adhes" user "B.Adhesive")
		(13 "F.Paste" user "Top Paste")
		(15 "B.Paste" user "Bottom Paste")
		(5 "F.SilkS" user "Top Overlay")
		(7 "B.SilkS" user "Bottom Overlay")
		(1 "F.Mask" user "Top Solder")
		(3 "B.Mask" user "Bottom Solder")
		(17 "Dwgs.User" user "User.Drawings")
		(19 "Cmts.User" user "User.Comments")
		(21 "Eco1.User" user "User.Eco1")
		(23 "Eco2.User" user "User.Eco2")
		(25 "Edge.Cuts" user)
		(27 "Margin" user)
		(31 "F.CrtYd" user "Top Courtyard")
		(29 "B.CrtYd" user "Bottom Courtyard")
		(35 "F.Fab" user "Top Component Center")
		(33 "B.Fab" user "Bottom Component Center")
	)
	(footprint "Vault:FP-0402-L_1_0_1-W_0_5_0_1-IPC_C"
		(layer "F.Cu")
		(at 236.3261 107.75066 -90)
		(property "Reference" "C18"
			(at -3.03446 0.393345 270)
			(unlocked yes)
			(layer "F.SilkS")
			(effects
				(font
					(size 0.762 0.762)
					(thickness 0.2286)
				)
				(justify left bottom)
			)
		)
		(property "Value" "0.1uF_25V_0402"
			(at 5.258585 -17.76611 0)
			(unlocked yes)
			(layer "F.SilkS")
			(hide yes)
			(effects
				(font
					(size 0.762 0.762)
					(thickness 0.2286)
				)
				(justify left bottom)
			)
		)
		(sheetname "POWER")
		(sheetfile "POWER.kicad_sch")
		(duplicate_pad_numbers_are_jumpers no)
		(fp_line
			(start 0.65607 0.7)
			(end -0.65606 0.7)
			(stroke
				(width 0.2)
				(type solid)
			)
			(layer "F.SilkS")
		)
		(fp_line
			(start 0.65607 -0.7)
			(end -0.65606 -0.7)
			(stroke
				(width 0.2)
				(type solid)
			)
			(layer "F.SilkS")
		)
		(fp_line
			(start -0.75606 0.4)
			(end -0.75606 -0.4)
			(stroke
				(width 0.2)
				(type solid)
			)
			(layer "F.CrtYd")
		)
		(fp_line
			(start 0.75607 0.4)
			(end -0.75606 0.4)
			(stroke
				(width 0.2)
				(type solid)
			)
			(layer "F.CrtYd")
		)
		(fp_line
			(start 0.75607 0.4)
			(end 0.75607 -0.4)
			(stroke
				(width 0.2)
				(type solid)
			)
			(layer "F.CrtYd")
		)
		(fp_line
			(start 0.75607 -0.4)
			(end -0.75606 -0.4)
			(stroke
				(width 0.2)
				(type solid)
			)
			(layer "F.CrtYd")
		)
		(fp_line
			(start 0 0.5)
			(end 0 -0.5)
			(stroke
				(width 0.1)
				(type solid)
			)
			(layer "F.Fab")
		)
		(fp_line
			(start -0.75606 0.4)
			(end -0.75606 -0.4)
			(stroke
				(width 0.2)
				(type solid)
			)
			(layer "F.Fab")
		)
		(fp_line
			(start 0.75607 0.4)
			(end -0.75606 0.4)
			(stroke
				(width 0.2)
				(type solid)
			)
			(layer "F.Fab")
		)
		(fp_line
			(start 0.75607 0.4)
			(end 0.75607 -0.4)
			(stroke
				(width 0.2)
				(type solid)
			)
			(layer "F.Fab")
		)
		(fp_line
			(start 0.5 0)
			(end -0.5 0)
			(stroke
				(width 0.1)
				(type solid)
			)
			(layer "F.Fab")
		)
		(fp_line
			(start 0.75607 -0.4)
			(end -0.75606 -0.4)
			(stroke
				(width 0.2)
				(type solid)
			)
			(layer "F.Fab")
		)
		(fp_text user "${REFERENCE}"
			(at -0.00001 0.09602 270)
			(unlocked yes)
			(layer "F.Fab")
			(effects
				(font
					(face "Arial")
					(size 0.63 0.63)
					(thickness 0.1)
				)
				(justify left bottom)
			)
		)
		(pad "1" smd rect
			(at -0.36553 0 270)
			(size 0.58106 0.51213)
			(layers "F.Cu" "F.Mask" "F.Paste")
			(net "+5.0V")
			(solder_mask_margin 0)
			(solder_paste_margin 0)
		)
		(pad "2" smd rect
			(at 0.36554 0 270)
			(size 0.58106 0.51213)
			(layers "F.Cu" "F.Mask" "F.Paste")
			(net "GND")
			(solder_mask_margin 0)
			(solder_paste_margin 0)
		)
	)
	(footprint "Vault:FP-LTST-C191TBKT-MFG"
		(layer "F.Cu")
		(at 75.1261 52.1162 90)
		(property "Reference" "D11"
			(at -7.75 0.343345 90)
			(unlocked yes)
			(layer "F.SilkS")
			(effects
				(font
					(size 0.762 0.762)
					(thickness 0.2286)
				)
				(justify left bottom)
			)
		)
		(property "Value" "BLUE"
			(at -3.128645 -1.4097 0)
			(unlocked yes)
			(layer "F.SilkS")
			(hide yes)
			(effects
				(font
					(size 0.762 0.762)
					(thickness 0.2286)
				)
				(justify left bottom)
			)
		)
		(sheetname "USER_IO_STATUS")
		(sheetfile "USER_IO_STATUS.kicad_sch")
		(duplicate_pad_numbers_are_jumpers no)
		(fp_line
			(start -0.85 -0.8)
			(end 0.85 -0.8)
			(stroke
				(width 0.2)
				(type solid)
			)
			(layer "F.SilkS")
		)
		(fp_line
			(start -0.85 0.8)
			(end 0.85 0.8)
			(stroke
				(width 0.2)
				(type solid)
			)
			(layer "F.SilkS")
		)
		(fp_circle
			(center -1.75 0)
			(end -1.625 0)
			(stroke
				(width 0.25)
				(type solid)
			)
			(fill no)
			(layer "F.SilkS")
		)
		(fp_line
			(start 1.25 -0.55)
			(end 1.25 0.55)
			(stroke
				(width 0.2)
				(type solid)
			)
			(layer "F.CrtYd")
		)
		(fp_line
			(start -1.25 -0.55)
			(end 1.25 -0.55)
			(stroke
				(width 0.2)
				(type solid)
			)
			(layer "F.CrtYd")
		)
		(fp_line
			(start -1.25 -0.55)
			(end -1.25 0.55)
			(stroke
				(width 0.2)
				(type solid)
			)
			(layer "F.CrtYd")
		)
		(fp_line
			(start -1.25 0.55)
			(end 1.25 0.55)
			(stroke
				(width 0.2)
				(type solid)
			)
			(layer "F.CrtYd")
		)
		(fp_line
			(start 1.25 -0.55)
			(end 1.25 0.55)
			(stroke
				(width 0.2)
				(type solid)
			)
			(layer "F.Fab")
		)
		(fp_line
			(start -1.25 -0.55)
			(end 1.25 -0.55)
			(stroke
				(width 0.2)
				(type solid)
			)
			(layer "F.Fab")
		)
		(fp_line
			(start -1.25 -0.55)
			(end -1.25 0.55)
			(stroke
				(width 0.2)
				(type solid)
			)
			(layer "F.Fab")
		)
		(fp_line
			(start 0 -0.5)
			(end 0 0.5)
			(stroke
				(width 0.1)
				(type solid)
			)
			(layer "F.Fab")
		)
		(fp_line
			(start -0.5 0)
			(end 0.5 0)
			(stroke
				(width 0.1)
				(type solid)
			)
			(layer "F.Fab")
		)
		(fp_line
			(start -1.25 0.55)
			(end 1.25 0.55)
			(stroke
				(width 0.2)
				(type solid)
			)
			(layer "F.Fab")
		)
		(pad "1" smd rect
			(at -0.75 0 90)
			(size 0.8 0.8)
			(layers "F.Cu" "F.Mask" "F.Paste")
			(net "NetD11_1")
			(solder_mask_margin 0)
			(solder_paste_margin 0)
		)
		(pad "2" smd rect
			(at 0.75 0 90)
			(size 0.8 0.8)
			(layers "F.Cu" "F.Mask" "F.Paste")
			(net "+3.3V")
			(solder_mask_margin 0)
			(solder_paste_margin 0)
		)
	)
	(footprint "Vault:FP-0402-L_1_0_0_05-W_0_5-IPC_A"
		(layer "F.Cu")
		(at 236.69996 102.15182 90)
		(property "Reference" "C17"
			(at 3.33562 -0.667205 270)
			(unlocked yes)
			(layer "F.SilkS")
			(effects
				(font
					(size 0.762 0.762)
					(thickness 0.2286)
				)
				(justify left bottom)
			)
		)
		(property "Value" "1uF_16V_0402"
			(at -6.793035 11.9755 0)
			(unlocked yes)
			(layer "F.SilkS")
			(hide yes)
			(effects
				(font
					(size 0.762 0.762)
					(thickness 0.2286)
				)
				(justify left bottom)
			)
		)
		(sheetname "POWER")
		(sheetfile "POWER.kicad_sch")
		(duplicate_pad_numbers_are_jumpers no)
		(fp_line
			(start -0.83623 -0.73623)
			(end 0.83624 -0.73623)
			(stroke
				(width 0.2)
				(type solid)
			)
			(layer "F.SilkS")
		)
		(fp_line
			(start -0.83623 0.73624)
			(end 0.83624 0.73624)
			(stroke
				(width 0.2)
				(type solid)
			)
			(layer "F.SilkS")
		)
		(fp_line
			(start 1.03624 -0.53623)
			(end 1.03624 0.53624)
			(stroke
				(width 0.2)
				(type solid)
			)
			(layer "F.CrtYd")
		)
		(fp_line
			(start -1.03623 -0.53623)
			(end 1.03624 -0.53623)
			(stroke
				(width 0.2)
				(type solid)
			)
			(layer "F.CrtYd")
		)
		(fp_line
			(start -1.03623 -0.53623)
			(end -1.03623 0.53624)
			(stroke
				(width 0.2)
				(type solid)
			)
			(layer "F.CrtYd")
		)
		(fp_line
			(start -1.03623 0.53624)
			(end 1.03624 0.53624)
			(stroke
				(width 0.2)
				(type solid)
			)
			(layer "F.CrtYd")
		)
		(fp_line
			(start 1.03624 -0.53623)
			(end 1.03624 0.53624)
			(stroke
				(width 0.2)
				(type solid)
			)
			(layer "F.Fab")
		)
		(fp_line
			(start -1.03623 -0.53623)
			(end 1.03624 -0.53623)
			(stroke
				(width 0.2)
				(type solid)
			)
			(layer "F.Fab")
		)
		(fp_line
			(start -1.03623 -0.53623)
			(end -1.03623 0.53624)
			(stroke
				(width 0.2)
				(type solid)
			)
			(layer "F.Fab")
		)
		(fp_line
			(start 0 -0.5)
			(end 0 0.5)
			(stroke
				(width 0.1)
				(type solid)
			)
			(layer "F.Fab")
		)
		(fp_line
			(start -0.5 0)
			(end 0.5 0)
			(stroke
				(width 0.1)
				(type solid)
			)
			(layer "F.Fab")
		)
		(fp_line
			(start -1.03623 0.53624)
			(end 1.03624 0.53624)
			(stroke
				(width 0.2)
				(type solid)
			)
			(layer "F.Fab")
		)
		(fp_text user "${REFERENCE}"
			(at -0.00001 0.09602 90)
			(unlocked yes)
			(layer "F.Fab")
			(effects
				(font
					(face "Arial")
					(size 0.63 0.63)
					(thickness 0.1)
				)
				(justify left bottom)
			)
		)
		(pad "1" smd rect
			(at -0.47856 0 90)
			(size 0.71535 0.67248)
			(layers "F.Cu" "F.Mask" "F.Paste")
			(net "+5.0V")
			(solder_mask_margin 0)
			(solder_paste_margin 0)
		)
		(pad "2" smd rect
			(at 0.47857 0 90)
			(size 0.71535 0.67248)
			(layers "F.Cu" "F.Mask" "F.Paste")
			(net "GND")
			(solder_mask_margin 0)
			(solder_paste_margin 0)
		)
	)
	(footprint "Vault:AMPH-901-143-6RFX_V"
		(layer "F.Cu")
		(at 60.9761 122.0782 180)
		(property "Reference" "AN3"
			(at -5.917345 2.516 90)
			(unlocked yes)
			(layer "F.SilkS")
			(effects
				(font
					(size 0.762 0.762)
					(thickness 0.2286)
				)
				(justify left bottom)
			)
		)
		(property "Value" "RF2-49B-T-00-50-G-HDW"
			(at 4.6101 -1.960245 0)
			(unlocked yes)
			(layer "F.SilkS")
			(hide yes)
			(effects
				(font
					(size 0.762 0.762)
					(thickness 0.2286)
				)
				(justify left bottom)
			)
		)
		(sheetname "USER_IO")
		(sheetfile "USER_IO.kicad_sch")
		(duplicate_pad_numbers_are_jumpers no)
		(fp_line
			(start 3.5 -1.38)
			(end 3.5 1.38)
			(stroke
				(width 0.2)
				(type solid)
			)
			(layer "F.SilkS")
		)
		(fp_line
			(start 1.38 3.5)
			(end -1.38 3.5)
			(stroke
				(width 0.2)
				(type solid)
			)
			(layer "F.SilkS")
		)
		(fp_line
			(start 1.38 -3.5)
			(end -1.38 -3.5)
			(stroke
				(width 0.2)
				(type solid)
			)
			(layer "F.SilkS")
		)
		(fp_line
			(start -3.5 -1.38)
			(end -3.5 1.38)
			(stroke
				(width 0.2)
				(type solid)
			)
			(layer "F.SilkS")
		)
		(pad "1" thru_hole rect
			(at 0 0 180)
			(size 2 2)
			(drill 1.5)
			(layers "*.Cu" "*.Mask")
			(remove_unused_layers no)
			(net "NetAN3_1")
		)
		(pad "2" thru_hole circle
			(at -2.54 -2.54 180)
			(size 2.2 2.2)
			(drill 1.7)
			(layers "*.Cu" "*.Mask")
			(remove_unused_layers no)
			(net "GND")
			(thermal_bridge_angle 90)
		)
		(pad "3" thru_hole circle
			(at -2.54 2.54 180)
			(size 2.2 2.2)
			(drill 1.7)
			(layers "*.Cu" "*.Mask")
			(remove_unused_layers no)
			(net "GND")
			(thermal_bridge_angle 90)
		)
		(pad "4" thru_hole circle
			(at 2.54 2.54 180)
			(size 2.2 2.2)
			(drill 1.7)
			(layers "*.Cu" "*.Mask")
			(remove_unused_layers no)
			(net "GND")
			(thermal_bridge_angle 90)
		)
		(pad "5" thru_hole circle
			(at 2.54 -2.54 180)
			(size 2.2 2.2)
			(drill 1.7)
			(layers "*.Cu" "*.Mask")
			(remove_unused_layers no)
			(net "GND")
			(thermal_bridge_angle 90)
		)
	)
	(footprint "Vault:FP-5TS1-IPC_C"
		(layer "F.Cu")
		(at 180.1261 87.0786 -90)
		(property "Reference" "U7"
			(at -2.735469 -0.228595 0)
			(unlocked yes)
			(layer "F.SilkS")
			(effects
				(font
					(size 0.762 0.762)
					(thickness 0.2286)
				)
			)
		)
		(property "Value" "AT24MAC402-STUM-T"
			(at 10.727395 3.189471 270)
			(unlocked yes)
			(layer "F.SilkS")
			(hide yes)
			(effects
				(font
					(size 0.762 0.762)
					(thickness 0.2286)
				)
			)
		)
		(sheetname "GPS_IMU_SENSORS")
		(sheetfile "GPS_IMU_SENSORS.kicad_sch")
		(duplicate_pad_numbers_are_jumpers no)
		(fp_line
			(start 0.17207 1.45)
			(end -0.17207 1.45)
			(stroke
				(width 0.2)
				(type solid)
			)
			(layer "F.SilkS")
		)
		(fp_line
			(start 0.8 0.30894)
			(end 0.8 -0.30893)
			(stroke
				(width 0.2)
				(type solid)
			)
			(layer "F.SilkS")
		)
		(fp_line
			(start 0.17207 -1.45)
			(end -0.17207 -1.45)
			(stroke
				(width 0.2)
				(type solid)
			)
			(layer "F.SilkS")
		)
		(fp_circle
			(center -2.21035 -0.95)
			(end -2.33535 -0.95)
			(stroke
				(width 0.25)
				(type solid)
			)
			(fill no)
			(layer "F.SilkS")
		)
		(fp_line
			(start -1.68536 1.55)
			(end -1.68536 -1.55)
			(stroke
				(width 0.2)
				(type solid)
			)
			(layer "F.CrtYd")
		)
		(fp_line
			(start 1.68536 1.55)
			(end -1.68536 1.55)
			(stroke
				(width 0.2)
				(type solid)
			)
			(layer "F.CrtYd")
		)
		(fp_line
			(start 1.68536 1.55)
			(end 1.68536 -1.55)
			(stroke
				(width 0.2)
				(type solid)
			)
			(layer "F.CrtYd")
		)
		(fp_line
			(start 1.68536 -1.55)
			(end -1.68536 -1.55)
			(stroke
				(width 0.2)
				(type solid)
			)
			(layer "F.CrtYd")
		)
		(fp_line
			(start -1.68536 1.55)
			(end -1.68536 -1.55)
			(stroke
				(width 0.2)
				(type solid)
			)
			(layer "F.Fab")
		)
		(fp_line
			(start 1.68536 1.55)
			(end -1.68536 1.55)
			(stroke
				(width 0.2)
				(type solid)
			)
			(layer "F.Fab")
		)
		(fp_line
			(start 1.68536 1.55)
			(end 1.68536 -1.55)
			(stroke
				(width 0.2)
				(type solid)
			)
			(layer "F.Fab")
		)
		(fp_line
			(start 0 0.5)
			(end 0 -0.5)
			(stroke
				(width 0.1)
				(type solid)
			)
			(layer "F.Fab")
		)
		(fp_line
			(start 0.5 0)
			(end -0.5 0)
			(stroke
				(width 0.1)
				(type solid)
			)
			(layer "F.Fab")
		)
		(fp_line
			(start 1.68536 -1.55)
			(end -1.68536 -1.55)
			(stroke
				(width 0.2)
				(type solid)
			)
			(layer "F.Fab")
		)
		(fp_text user "${REFERENCE}"
			(at 0 0.28425 270)
			(unlocked yes)
			(layer "F.Fab")
			(effects
				(font
					(face "Arial")
					(size 0.63 0.63)
					(thickness 0.1)
				)
				(justify left bottom)
			)
		)
		(pad "1" smd rect
			(at -1.06621 -0.95 270)
			(size 1.03828 0.53213)
			(layers "F.Cu" "F.Mask" "F.Paste")
			(net "SCL")
			(solder_mask_margin 0)
			(solder_paste_margin 0)
		)
		(pad "2" smd roundrect
			(at -1.06621 0 270)
			(size 1.03828 0.53213)
			(layers "F.Cu" "F.Mask" "F.Paste")
			(roundrect_rratio 0.5)
			(net "GND")
			(solder_mask_margin 0)
			(solder_paste_margin 0)
		)
		(pad "3" smd roundrect
			(at -1.06621 0.95 270)
			(size 1.03828 0.53213)
			(layers "F.Cu" "F.Mask" "F.Paste")
			(roundrect_rratio 0.5)
			(net "SDA")
			(solder_mask_margin 0)
			(solder_paste_margin 0)
		)
		(pad "4" smd roundrect
			(at 1.06621 0.95 270)
			(size 1.03828 0.53213)
			(layers "F.Cu" "F.Mask" "F.Paste")
			(roundrect_rratio 0.5)
			(net "+3.3V")
			(solder_mask_margin 0)
			(solder_paste_margin 0)
		)
		(pad "5" smd roundrect
			(at 1.06621 -0.95 270)
			(size 1.03828 0.53213)
			(layers "F.Cu" "F.Mask" "F.Paste")
			(roundrect_rratio 0.5)
			(net "EXT_EEPROM_WP")
			(solder_mask_margin 0)
			(solder_paste_margin 0)
		)
	)
	(footprint "Vault:FP-C3216-160-0_2-MFG"
		(layer "F.Cu")
		(at 234.7261 102.0162 90)
		(property "Reference" "C13"
			(at 4.6 -0.493345 270)
			(unlocked yes)
			(layer "F.SilkS")
			(effects
				(font
					(size 0.762 0.762)
					(thickness 0.2286)
				)
				(justify left bottom)
			)
		)
		(property "Value" "47uF_16V_1206"
			(at -9.997845 1.3401 0)
			(unlocked yes)
			(layer "F.SilkS")
			(hide yes)
			(effects
				(font
					(size 0.762 0.762)
					(thickness 0.2286)
				)
				(justify left bottom)
			)
		)
		(sheetname "POWER")
		(sheetfile "POWER.kicad_sch")
		(duplicate_pad_numbers_are_jumpers no)
		(fp_line
			(start -0.725 -0.9)
			(end 0.725 -0.9)
			(stroke
				(width 0.2)
				(type solid)
			)
			(layer "F.SilkS")
		)
		(fp_line
			(start -0.725 0.9)
			(end 0.725 0.9)
			(stroke
				(width 0.2)
				(type solid)
			)
			(layer "F.SilkS")
		)
		(fp_line
			(start 2.3 -1)
			(end 2.3 1)
			(stroke
				(width 0.2)
				(type solid)
			)
			(layer "F.CrtYd")
		)
		(fp_line
			(start -2.3 -1)
			(end 2.3 -1)
			(stroke
				(width 0.2)
				(type solid)
			)
			(layer "F.CrtYd")
		)
		(fp_line
			(start -2.3 -1)
			(end -2.3 1)
			(stroke
				(width 0.2)
				(type solid)
			)
			(layer "F.CrtYd")
		)
		(fp_line
			(start -2.3 1)
			(end 2.3 1)
			(stroke
				(width 0.2)
				(type solid)
			)
			(layer "F.CrtYd")
		)
		(fp_line
			(start 2.3 -1)
			(end 2.3 1)
			(stroke
				(width 0.2)
				(type solid)
			)
			(layer "F.Fab")
		)
		(fp_line
			(start -2.3 -1)
			(end 2.3 -1)
			(stroke
				(width 0.2)
				(type solid)
			)
			(layer "F.Fab")
		)
		(fp_line
			(start -2.3 -1)
			(end -2.3 1)
			(stroke
				(width 0.2)
				(type solid)
			)
			(layer "F.Fab")
		)
		(fp_line
			(start 0 -0.5)
			(end 0 0.5)
			(stroke
				(width 0.1)
				(type solid)
			)
			(layer "F.Fab")
		)
		(fp_line
			(start -0.5 0)
			(end 0.5 0)
			(stroke
				(width 0.1)
				(type solid)
			)
			(layer "F.Fab")
		)
		(fp_line
			(start -2.3 1)
			(end 2.3 1)
			(stroke
				(width 0.2)
				(type solid)
			)
			(layer "F.Fab")
		)
		(fp_text user "${REFERENCE}"
			(at -0.00001 0.09601 90)
			(unlocked yes)
			(layer "F.Fab")
			(effects
				(font
					(face "Arial")
					(size 0.63 0.63)
					(thickness 0.1)
				)
				(justify left bottom)
			)
		)
		(pad "1" smd rect
			(at -1.65 0 90)
			(size 1.1 1.35)
			(layers "F.Cu" "F.Mask" "F.Paste")
			(net "+5.0V")
			(solder_mask_margin 0)
			(solder_paste_margin 0)
		)
		(pad "2" smd rect
			(at 1.65 0 90)
			(size 1.1 1.35)
			(layers "F.Cu" "F.Mask" "F.Paste")
			(net "GND")
			(solder_mask_margin 0)
			(solder_paste_margin 0)
		)
	)
	(footprint "Vault:RESC1005X40X25NL05T05"
		(layer "F.Cu")
		(at 214.0261 76.7162 -90)
		(property "Reference" "R90"
			(at -2.2714 0.326931 270)
			(unlocked yes)
			(layer "F.SilkS")
			(effects
				(font
					(size 0.762 0.762)
					(thickness 0.2286)
				)
			)
		)
		(property "Value" "27_1%_0402"
			(at -2.732271 7.37632 180)
			(unlocked yes)
			(layer "F.SilkS")
			(hide yes)
			(effects
				(font
					(size 0.762 0.762)
					(thickness 0.2286)
				)
			)
		)
		(sheetname "USBUart_DipSelects")
		(sheetfile "USBUart_DipSelects.kicad_sch")
		(duplicate_pad_numbers_are_jumpers no)
		(pad "1" smd rect
			(at -0.45 0)
			(size 0.55 0.55)
			(layers "F.Cu" "F.Mask" "F.Paste")
			(net "FTDI_RX")
		)
		(pad "2" smd rect
			(at 0.45 0)
			(size 0.55 0.55)
			(layers "F.Cu" "F.Mask" "F.Paste")
			(net "NetR90_2")
		)
	)
	(footprint "Vault:RESC1005X40X25NL05T05"
		(layer "F.Cu")
		(at 232.7261 75.7162 90)
		(property "Reference" "R43"
			(at 0.3714 -4.826931 270)
			(unlocked yes)
			(layer "F.SilkS")
			(effects
				(font
					(size 0.762 0.762)
					(thickness 0.2286)
				)
			)
		)
		(property "Value" "27_1%_0402"
			(at -3.011631 6.10665 0)
			(unlocked yes)
			(layer "F.SilkS")
			(hide yes)
			(effects
				(font
					(size 0.762 0.762)
					(thickness 0.2286)
				)
			)
		)
		(sheetname "USBUart_DipSelects")
		(sheetfile "USBUart_DipSelects.kicad_sch")
		(duplicate_pad_numbers_are_jumpers no)
		(pad "1" smd rect
			(at -0.45 0 180)
			(size 0.55 0.55)
			(layers "F.Cu" "F.Mask" "F.Paste")
			(net "FTDI_USB_R_N")
		)
		(pad "2" smd rect
			(at 0.45 0 180)
			(size 0.55 0.55)
			(layers "F.Cu" "F.Mask" "F.Paste")
			(net "FTDI_USB_N")
		)
	)
)
